(kicad_pcb
	(version 20260206)
	(generator "pcbnew")
	(generator_version "10.0")
	(general
		(thickness 1.6)
		(legacy_teardrops no)
	)
	(paper "A4")
	(title_block
		(title "9054_F0T_PDB_BD_GPU_F_V04_1213_1550_OCP.brd")
		(comment 1 "Grand Teton / footprints 536-542 of 608")
	)
	(layers
		(0 "F.Cu" signal "TOP")
		(4 "In1.Cu" signal "GND")
		(6 "In2.Cu" signal "IN1")
		(8 "In3.Cu" signal "GND1")
		(10 "In4.Cu" signal "VCC")
		(12 "In5.Cu" signal "VCC1")
		(14 "In6.Cu" signal "GND2")
		(16 "In7.Cu" signal "IN2")
		(18 "In8.Cu" signal "GND3")
		(2 "B.Cu" signal "BOTTOM")
		(9 "F.Adhes" user "F.Adhesive")
		(11 "B.Adhes" user "B.Adhesive")
		(13 "F.Paste" user "Package Geometry/Pastemask Top")
		(15 "B.Paste" user "Package Geometry/Pastemask Bottom")
		(5 "F.SilkS" user "Ref Des/Silkscreen Top")
		(7 "B.SilkS" user "Ref Des/Silkscreen Bottom")
		(1 "F.Mask" user "Board Geometry/Soldermask Top")
		(3 "B.Mask" user "Board Geometry/Soldermask Bottom")
		(17 "Dwgs.User" user "User.Drawings")
		(19 "Cmts.User" user "User.Comments")
		(21 "Eco1.User" user "User.Eco1")
		(23 "Eco2.User" user "User.Eco2")
		(25 "Edge.Cuts" user "Board Geometry/Outline")
		(27 "Margin" user)
		(31 "F.CrtYd" user "Package Geometry/Place Bound Top")
		(29 "B.CrtYd" user "Package Geometry/Place Bound Bottom")
		(35 "F.Fab" user "Ref Des/Assembly Top")
		(33 "B.Fab" user "Ref Des/Assembly Bottom")
	)
	(footprint ""
		(layer "B.Cu")
		(at 106.045 -52.324 90)
		(property "Reference" "PC594"
			(at 0 0 90)
			(layer "B.SilkS")
			(hide yes)
			(effects
				(font
					(size 1.27 1.27)
				)
				(justify mirror)
			)
		)
		(property "Value" ""
			(at 0 0 90)
			(layer "B.Fab")
			(effects
				(font
					(size 1.27 1.27)
				)
				(justify mirror)
			)
		)
		(duplicate_pad_numbers_are_jumpers no)
		(fp_line
			(start 1.2954 -0.5842)
			(end -1.2954 -0.5842)
			(stroke
				(width 0.1524)
				(type default)
			)
			(layer "B.SilkS")
		)
		(fp_line
			(start -1.2954 -0.5842)
			(end -1.2954 0.5842)
			(stroke
				(width 0.1524)
				(type default)
			)
			(layer "B.SilkS")
		)
		(fp_line
			(start 1.2954 0.5842)
			(end 1.2954 -0.5842)
			(stroke
				(width 0.1524)
				(type default)
			)
			(layer "B.SilkS")
		)
		(fp_line
			(start -1.2954 0.5842)
			(end 1.2954 0.5842)
			(stroke
				(width 0.1524)
				(type default)
			)
			(layer "B.SilkS")
		)
		(fp_line
			(start 0.8636 -0.4572)
			(end -0.8636 -0.4572)
			(stroke
				(width 0.1)
				(type default)
			)
			(layer "B.Fab")
		)
		(fp_line
			(start -0.8636 -0.4572)
			(end -0.8636 -0.4064)
			(stroke
				(width 0.1)
				(type default)
			)
			(layer "B.Fab")
		)
		(fp_line
			(start 1.1938 -0.4064)
			(end 0.8636 -0.4064)
			(stroke
				(width 0.1)
				(type default)
			)
			(layer "B.Fab")
		)
		(fp_line
			(start 0.8636 -0.4064)
			(end 0.8636 -0.4572)
			(stroke
				(width 0.1)
				(type default)
			)
			(layer "B.Fab")
		)
		(fp_line
			(start -0.8636 -0.4064)
			(end -1.1938 -0.4064)
			(stroke
				(width 0.1)
				(type default)
			)
			(layer "B.Fab")
		)
		(fp_line
			(start -1.1938 -0.4064)
			(end -1.1938 0.4064)
			(stroke
				(width 0.1)
				(type default)
			)
			(layer "B.Fab")
		)
		(fp_line
			(start 1.1938 0.4064)
			(end 1.1938 -0.4064)
			(stroke
				(width 0.1)
				(type default)
			)
			(layer "B.Fab")
		)
		(fp_line
			(start 0.8636 0.4064)
			(end 1.1938 0.4064)
			(stroke
				(width 0.1)
				(type default)
			)
			(layer "B.Fab")
		)
		(fp_line
			(start -0.8636 0.4064)
			(end -0.8636 0.4572)
			(stroke
				(width 0.1)
				(type default)
			)
			(layer "B.Fab")
		)
		(fp_line
			(start -1.1938 0.4064)
			(end -0.8636 0.4064)
			(stroke
				(width 0.1)
				(type default)
			)
			(layer "B.Fab")
		)
		(fp_line
			(start 0.8636 0.4572)
			(end 0.8636 0.4064)
			(stroke
				(width 0.1)
				(type default)
			)
			(layer "B.Fab")
		)
		(fp_line
			(start -0.8636 0.4572)
			(end 0.8636 0.4572)
			(stroke
				(width 0.1)
				(type default)
			)
			(layer "B.Fab")
		)
		(pad "1" smd rect
			(at 0.7366 0)
			(size 0.7112 0.8128)
			(layers "B.Cu" "B.Mask" "B.Paste")
			(net "P52V_HS2_4287_GATE_R")
		)
		(pad "2" smd rect
			(at -0.7366 0)
			(size 0.7112 0.8128)
			(layers "B.Cu" "B.Mask" "B.Paste")
			(net "P52V_HS2")
		)
	)
	(footprint ""
		(layer "B.Cu")
		(at 106.045 -43.815 -90)
		(property "Reference" "PR7003"
			(at 0 0 90)
			(layer "B.SilkS")
			(hide yes)
			(effects
				(font
					(size 1.27 1.27)
				)
				(justify mirror)
			)
		)
		(property "Value" ""
			(at 0 0 90)
			(layer "B.Fab")
			(effects
				(font
					(size 1.27 1.27)
				)
				(justify mirror)
			)
		)
		(duplicate_pad_numbers_are_jumpers no)
		(fp_line
			(start -1.2954 0.5842)
			(end 1.2954 0.5842)
			(stroke
				(width 0.1524)
				(type default)
			)
			(layer "B.SilkS")
		)
		(fp_line
			(start 1.2954 0.5842)
			(end 1.2954 -0.5842)
			(stroke
				(width 0.1524)
				(type default)
			)
			(layer "B.SilkS")
		)
		(fp_line
			(start -1.2954 -0.5842)
			(end -1.2954 0.5842)
			(stroke
				(width 0.1524)
				(type default)
			)
			(layer "B.SilkS")
		)
		(fp_line
			(start 1.2954 -0.5842)
			(end -1.2954 -0.5842)
			(stroke
				(width 0.1524)
				(type default)
			)
			(layer "B.SilkS")
		)
		(fp_line
			(start -0.8636 0.4572)
			(end 0.8636 0.4572)
			(stroke
				(width 0.1)
				(type default)
			)
			(layer "B.Fab")
		)
		(fp_line
			(start 0.8636 0.4572)
			(end 0.8636 0.4318)
			(stroke
				(width 0.1)
				(type default)
			)
			(layer "B.Fab")
		)
		(fp_line
			(start 0.8636 0.4318)
			(end 0.8636 0.4064)
			(stroke
				(width 0.1)
				(type default)
			)
			(layer "B.Fab")
		)
		(fp_line
			(start -1.1938 0.4064)
			(end -0.8636 0.4064)
			(stroke
				(width 0.1)
				(type default)
			)
			(layer "B.Fab")
		)
		(fp_line
			(start -0.8636 0.4064)
			(end -0.8636 0.4572)
			(stroke
				(width 0.1)
				(type default)
			)
			(layer "B.Fab")
		)
		(fp_line
			(start 0.8636 0.4064)
			(end 1.1938 0.4064)
			(stroke
				(width 0.1)
				(type default)
			)
			(layer "B.Fab")
		)
		(fp_line
			(start 1.1938 0.4064)
			(end 1.1938 -0.406654)
			(stroke
				(width 0.1)
				(type default)
			)
			(layer "B.Fab")
		)
		(fp_line
			(start -1.1938 -0.406654)
			(end -1.1938 0.4064)
			(stroke
				(width 0.1)
				(type default)
			)
			(layer "B.Fab")
		)
		(fp_line
			(start -0.8636 -0.406654)
			(end -1.1938 -0.406654)
			(stroke
				(width 0.1)
				(type default)
			)
			(layer "B.Fab")
		)
		(fp_line
			(start 0.8636 -0.406654)
			(end 0.8636 -0.4572)
			(stroke
				(width 0.1)
				(type default)
			)
			(layer "B.Fab")
		)
		(fp_line
			(start 1.1938 -0.406654)
			(end 0.8636 -0.406654)
			(stroke
				(width 0.1)
				(type default)
			)
			(layer "B.Fab")
		)
		(fp_line
			(start -0.8636 -0.4572)
			(end -0.8636 -0.406654)
			(stroke
				(width 0.1)
				(type default)
			)
			(layer "B.Fab")
		)
		(fp_line
			(start 0.8636 -0.4572)
			(end -0.8636 -0.4572)
			(stroke
				(width 0.1)
				(type default)
			)
			(layer "B.Fab")
		)
		(pad "1" smd rect
			(at 0.7366 0 180)
			(size 0.7112 0.8128)
			(layers "B.Cu" "B.Mask" "B.Paste")
			(net "P52V_HS2_4287_GATE2_R")
		)
		(pad "2" smd rect
			(at -0.7366 0 180)
			(size 0.7112 0.8128)
			(layers "B.Cu" "B.Mask" "B.Paste")
			(net "P52V_HS2_4287_GATE2_RC")
		)
	)
	(footprint ""
		(layer "B.Cu")
		(at 297.3324 -79.248)
		(property "Reference" "PR23"
			(at 0 0 0)
			(layer "B.SilkS")
			(hide yes)
			(effects
				(font
					(size 1.27 1.27)
				)
				(justify mirror)
			)
		)
		(property "Value" ""
			(at 0 0 0)
			(layer "B.Fab")
			(effects
				(font
					(size 1.27 1.27)
				)
				(justify mirror)
			)
		)
		(duplicate_pad_numbers_are_jumpers no)
		(fp_line
			(start -1.651 -0.8382)
			(end -1.651 0.8382)
			(stroke
				(width 0.1524)
				(type default)
			)
			(layer "B.SilkS")
		)
		(fp_line
			(start -1.651 0.8382)
			(end 1.651 0.8382)
			(stroke
				(width 0.1524)
				(type default)
			)
			(layer "B.SilkS")
		)
		(fp_line
			(start 1.651 -0.8382)
			(end -1.651 -0.8382)
			(stroke
				(width 0.1524)
				(type default)
			)
			(layer "B.SilkS")
		)
		(fp_line
			(start 1.651 0.8382)
			(end 1.651 -0.8382)
			(stroke
				(width 0.1524)
				(type default)
			)
			(layer "B.SilkS")
		)
		(fp_line
			(start -1.560576 -0.7366)
			(end -1.524 -0.7366)
			(stroke
				(width 0.1)
				(type default)
			)
			(layer "B.Fab")
		)
		(fp_line
			(start -1.560576 0.7366)
			(end -1.560576 -0.7366)
			(stroke
				(width 0.1)
				(type default)
			)
			(layer "B.Fab")
		)
		(fp_line
			(start -1.524 -0.7366)
			(end 1.524 -0.7366)
			(stroke
				(width 0.1)
				(type default)
			)
			(layer "B.Fab")
		)
		(fp_line
			(start -1.524 0.7366)
			(end -1.560576 0.7366)
			(stroke
				(width 0.1)
				(type default)
			)
			(layer "B.Fab")
		)
		(fp_line
			(start 1.524 -0.7366)
			(end 1.559814 -0.7366)
			(stroke
				(width 0.1)
				(type default)
			)
			(layer "B.Fab")
		)
		(fp_line
			(start 1.524 0.7366)
			(end -1.524 0.7366)
			(stroke
				(width 0.1)
				(type default)
			)
			(layer "B.Fab")
		)
		(fp_line
			(start 1.559814 -0.7366)
			(end 1.559814 0.7366)
			(stroke
				(width 0.1)
				(type default)
			)
			(layer "B.Fab")
		)
		(fp_line
			(start 1.559814 0.7366)
			(end 1.524 0.7366)
			(stroke
				(width 0.1)
				(type default)
			)
			(layer "B.Fab")
		)
		(pad "1" smd rect
			(at 0.94996 0)
			(size 1.1176 1.3716)
			(layers "B.Cu" "B.Mask" "B.Paste")
			(net "P52V_HS1")
		)
		(pad "2" smd rect
			(at -0.94996 0)
			(size 1.1176 1.3716)
			(layers "B.Cu" "B.Mask" "B.Paste")
			(net "P52V_HS1_FB")
		)
	)
	(footprint ""
		(layer "B.Cu")
		(at 177.592736 -77.851 180)
		(property "Reference" "PR7025"
			(at 0 0 0)
			(layer "B.SilkS")
			(hide yes)
			(effects
				(font
					(size 1.27 1.27)
				)
				(justify mirror)
			)
		)
		(property "Value" ""
			(at 0 0 0)
			(layer "B.Fab")
			(effects
				(font
					(size 1.27 1.27)
				)
				(justify mirror)
			)
		)
		(duplicate_pad_numbers_are_jumpers no)
		(fp_line
			(start 0.7874 0.4064)
			(end 0.7874 -0.4064)
			(stroke
				(width 0.1524)
				(type default)
			)
			(layer "B.SilkS")
		)
		(fp_line
			(start 0.7874 -0.4064)
			(end -0.7874 -0.4064)
			(stroke
				(width 0.1524)
				(type default)
			)
			(layer "B.SilkS")
		)
		(fp_line
			(start -0.7874 0.4064)
			(end 0.7874 0.4064)
			(stroke
				(width 0.1524)
				(type default)
			)
			(layer "B.SilkS")
		)
		(fp_line
			(start -0.7874 -0.4064)
			(end -0.7874 0.4064)
			(stroke
				(width 0.1524)
				(type default)
			)
			(layer "B.SilkS")
		)
		(fp_line
			(start 0.67945 0.3048)
			(end 0.67945 -0.305054)
			(stroke
				(width 0.1)
				(type default)
			)
			(layer "B.Fab")
		)
		(fp_line
			(start 0.67945 -0.305054)
			(end 0.12065 -0.305054)
			(stroke
				(width 0.1)
				(type default)
			)
			(layer "B.Fab")
		)
		(fp_line
			(start 0.12065 0.3048)
			(end 0.67945 0.3048)
			(stroke
				(width 0.1)
				(type default)
			)
			(layer "B.Fab")
		)
		(fp_line
			(start 0.12065 0.2794)
			(end 0.12065 0.3048)
			(stroke
				(width 0.1)
				(type default)
			)
			(layer "B.Fab")
		)
		(fp_line
			(start 0.12065 -0.2794)
			(end -0.12065 -0.2794)
			(stroke
				(width 0.1)
				(type default)
			)
			(layer "B.Fab")
		)
		(fp_line
			(start 0.12065 -0.305054)
			(end 0.12065 -0.2794)
			(stroke
				(width 0.1)
				(type default)
			)
			(layer "B.Fab")
		)
		(fp_line
			(start -0.120396 0.3048)
			(end -0.120396 0.2794)
			(stroke
				(width 0.1)
				(type default)
			)
			(layer "B.Fab")
		)
		(fp_line
			(start -0.120396 0.2794)
			(end 0.12065 0.2794)
			(stroke
				(width 0.1)
				(type default)
			)
			(layer "B.Fab")
		)
		(fp_line
			(start -0.12065 -0.2794)
			(end -0.12065 -0.3048)
			(stroke
				(width 0.1)
				(type default)
			)
			(layer "B.Fab")
		)
		(fp_line
			(start -0.12065 -0.3048)
			(end -0.67945 -0.3048)
			(stroke
				(width 0.1)
				(type default)
			)
			(layer "B.Fab")
		)
		(fp_line
			(start -0.67945 0.3048)
			(end -0.120396 0.3048)
			(stroke
				(width 0.1)
				(type default)
			)
			(layer "B.Fab")
		)
		(fp_line
			(start -0.67945 -0.3048)
			(end -0.67945 0.3048)
			(stroke
				(width 0.1)
				(type default)
			)
			(layer "B.Fab")
		)
		(pad "1" smd circle
			(at 0.40005 0)
			(size 0 0)
			(layers "B.Cu" "B.Mask" "B.Paste")
			(net "P52V_HS2_PWRGIN")
		)
		(pad "2" smd circle
			(at -0.40005 0)
			(size 0 0)
			(layers "B.Cu" "B.Mask" "B.Paste")
			(net "GND1_FIELD_SIGNAL")
		)
	)
	(footprint ""
		(layer "B.Cu")
		(at 297.307 -90.17 -90)
		(property "Reference" "C105"
			(at 0 0 90)
			(layer "B.SilkS")
			(hide yes)
			(effects
				(font
					(size 1.27 1.27)
				)
				(justify mirror)
			)
		)
		(property "Value" ""
			(at 0 0 90)
			(layer "B.Fab")
			(effects
				(font
					(size 1.27 1.27)
				)
				(justify mirror)
			)
		)
		(duplicate_pad_numbers_are_jumpers no)
		(fp_line
			(start -0.7874 0.4064)
			(end 0.7874 0.4064)
			(stroke
				(width 0.1524)
				(type default)
			)
			(layer "B.SilkS")
		)
		(fp_line
			(start 0.7874 0.4064)
			(end 0.7874 -0.4064)
			(stroke
				(width 0.1524)
				(type default)
			)
			(layer "B.SilkS")
		)
		(fp_line
			(start -0.7874 -0.4064)
			(end -0.7874 0.4064)
			(stroke
				(width 0.1524)
				(type default)
			)
			(layer "B.SilkS")
		)
		(fp_line
			(start 0.7874 -0.4064)
			(end -0.7874 -0.4064)
			(stroke
				(width 0.1524)
				(type default)
			)
			(layer "B.SilkS")
		)
		(fp_line
			(start -0.67945 0.3048)
			(end -0.120396 0.3048)
			(stroke
				(width 0.1)
				(type default)
			)
			(layer "B.Fab")
		)
		(fp_line
			(start -0.120396 0.3048)
			(end -0.120396 0.2794)
			(stroke
				(width 0.1)
				(type default)
			)
			(layer "B.Fab")
		)
		(fp_line
			(start 0.12065 0.3048)
			(end 0.67945 0.3048)
			(stroke
				(width 0.1)
				(type default)
			)
			(layer "B.Fab")
		)
		(fp_line
			(start 0.67945 0.3048)
			(end 0.67945 -0.305054)
			(stroke
				(width 0.1)
				(type default)
			)
			(layer "B.Fab")
		)
		(fp_line
			(start -0.120396 0.2794)
			(end 0.12065 0.2794)
			(stroke
				(width 0.1)
				(type default)
			)
			(layer "B.Fab")
		)
		(fp_line
			(start 0.12065 0.2794)
			(end 0.12065 0.3048)
			(stroke
				(width 0.1)
				(type default)
			)
			(layer "B.Fab")
		)
		(fp_line
			(start -0.12065 -0.2794)
			(end -0.12065 -0.3048)
			(stroke
				(width 0.1)
				(type default)
			)
			(layer "B.Fab")
		)
		(fp_line
			(start 0.12065 -0.2794)
			(end -0.12065 -0.2794)
			(stroke
				(width 0.1)
				(type default)
			)
			(layer "B.Fab")
		)
		(fp_line
			(start -0.67945 -0.3048)
			(end -0.67945 0.3048)
			(stroke
				(width 0.1)
				(type default)
			)
			(layer "B.Fab")
		)
		(fp_line
			(start -0.12065 -0.3048)
			(end -0.67945 -0.3048)
			(stroke
				(width 0.1)
				(type default)
			)
			(layer "B.Fab")
		)
		(fp_line
			(start 0.12065 -0.305054)
			(end 0.12065 -0.2794)
			(stroke
				(width 0.1)
				(type default)
			)
			(layer "B.Fab")
		)
		(fp_line
			(start 0.67945 -0.305054)
			(end 0.12065 -0.305054)
			(stroke
				(width 0.1)
				(type default)
			)
			(layer "B.Fab")
		)
		(pad "1" smd circle
			(at 0.40005 0 90)
			(size 0 0)
			(layers "B.Cu" "B.Mask" "B.Paste")
			(net "GND")
		)
		(pad "2" smd circle
			(at -0.40005 0 90)
			(size 0 0)
			(layers "B.Cu" "B.Mask" "B.Paste")
			(net "P3V3_AUX")
		)
	)
	(footprint ""
		(layer "B.Cu")
		(at 267.3604 -62.738 180)
		(property "Reference" "PC13"
			(at 0 0 0)
			(layer "B.SilkS")
			(hide yes)
			(effects
				(font
					(size 1.27 1.27)
				)
				(justify mirror)
			)
		)
		(property "Value" ""
			(at 0 0 0)
			(layer "B.Fab")
			(effects
				(font
					(size 1.27 1.27)
				)
				(justify mirror)
			)
		)
		(duplicate_pad_numbers_are_jumpers no)
		(fp_line
			(start 1.524 0.762)
			(end 1.524 -0.762)
			(stroke
				(width 0.1524)
				(type default)
			)
			(layer "B.SilkS")
		)
		(fp_line
			(start 1.524 -0.762)
			(end -1.524 -0.762)
			(stroke
				(width 0.1524)
				(type default)
			)
			(layer "B.SilkS")
		)
		(fp_line
			(start -1.524 0.762)
			(end 1.524 0.762)
			(stroke
				(width 0.1524)
				(type default)
			)
			(layer "B.SilkS")
		)
		(fp_line
			(start -1.524 -0.762)
			(end -1.524 0.762)
			(stroke
				(width 0.1524)
				(type default)
			)
			(layer "B.SilkS")
		)
		(fp_line
			(start 1.1049 0.724916)
			(end -1.1049 0.724916)
			(stroke
				(width 0.1)
				(type default)
			)
			(layer "B.Fab")
		)
		(fp_line
			(start 1.1049 -0.724916)
			(end 1.1049 0.724916)
			(stroke
				(width 0.1)
				(type default)
			)
			(layer "B.Fab")
		)
		(fp_line
			(start -1.1049 0.724916)
			(end -1.1049 -0.724916)
			(stroke
				(width 0.1)
				(type default)
			)
			(layer "B.Fab")
		)
		(fp_line
			(start -1.1049 -0.724916)
			(end 1.1049 -0.724916)
			(stroke
				(width 0.1)
				(type default)
			)
			(layer "B.Fab")
		)
		(pad "1" smd rect
			(at 0.889 0 180)
			(size 1.016 1.27)
			(layers "B.Cu" "B.Mask" "B.Paste")
			(net "P52V_HS1_DV_DT")
		)
		(pad "2" smd rect
			(at -0.889 0 180)
			(size 1.016 1.27)
			(layers "B.Cu" "B.Mask" "B.Paste")
			(net "GND_FIELD_SIGNAL")
		)
	)
	(footprint ""
		(layer "B.Cu")
		(at 337.3374 -39.37 90)
		(property "Reference" "R5863"
			(at 0 0 90)
			(layer "B.SilkS")
			(hide yes)
			(effects
				(font
					(size 1.27 1.27)
				)
				(justify mirror)
			)
		)
		(property "Value" ""
			(at 0 0 90)
			(layer "B.Fab")
			(effects
				(font
					(size 1.27 1.27)
				)
				(justify mirror)
			)
		)
		(duplicate_pad_numbers_are_jumpers no)
		(fp_line
			(start 0.7874 -0.4064)
			(end -0.7874 -0.4064)
			(stroke
				(width 0.1524)
				(type default)
			)
			(layer "B.SilkS")
		)
		(fp_line
			(start -0.7874 -0.4064)
			(end -0.7874 0.4064)
			(stroke
				(width 0.1524)
				(type default)
			)
			(layer "B.SilkS")
		)
		(fp_line
			(start 0.7874 0.4064)
			(end 0.7874 -0.4064)
			(stroke
				(width 0.1524)
				(type default)
			)
			(layer "B.SilkS")
		)
		(fp_line
			(start -0.7874 0.4064)
			(end 0.7874 0.4064)
			(stroke
				(width 0.1524)
				(type default)
			)
			(layer "B.SilkS")
		)
		(fp_line
			(start 0.67945 -0.305054)
			(end 0.12065 -0.305054)
			(stroke
				(width 0.1)
				(type default)
			)
			(layer "B.Fab")
		)
		(fp_line
			(start 0.12065 -0.305054)
			(end 0.12065 -0.2794)
			(stroke
				(width 0.1)
				(type default)
			)
			(layer "B.Fab")
		)
		(fp_line
			(start -0.12065 -0.3048)
			(end -0.67945 -0.3048)
			(stroke
				(width 0.1)
				(type default)
			)
			(layer "B.Fab")
		)
		(fp_line
			(start -0.67945 -0.3048)
			(end -0.67945 0.3048)
			(stroke
				(width 0.1)
				(type default)
			)
			(layer "B.Fab")
		)
		(fp_line
			(start 0.12065 -0.2794)
			(end -0.12065 -0.2794)
			(stroke
				(width 0.1)
				(type default)
			)
			(layer "B.Fab")
		)
		(fp_line
			(start -0.12065 -0.2794)
			(end -0.12065 -0.3048)
			(stroke
				(width 0.1)
				(type default)
			)
			(layer "B.Fab")
		)
		(fp_line
			(start 0.12065 0.2794)
			(end 0.12065 0.3048)
			(stroke
				(width 0.1)
				(type default)
			)
			(layer "B.Fab")
		)
		(fp_line
			(start -0.120396 0.2794)
			(end 0.12065 0.2794)
			(stroke
				(width 0.1)
				(type default)
			)
			(layer "B.Fab")
		)
		(fp_line
			(start 0.67945 0.3048)
			(end 0.67945 -0.305054)
			(stroke
				(width 0.1)
				(type default)
			)
			(layer "B.Fab")
		)
		(fp_line
			(start 0.12065 0.3048)
			(end 0.67945 0.3048)
			(stroke
				(width 0.1)
				(type default)
			)
			(layer "B.Fab")
		)
		(fp_line
			(start -0.120396 0.3048)
			(end -0.120396 0.2794)
			(stroke
				(width 0.1)
				(type default)
			)
			(layer "B.Fab")
		)
		(fp_line
			(start -0.67945 0.3048)
			(end -0.120396 0.3048)
			(stroke
				(width 0.1)
				(type default)
			)
			(layer "B.Fab")
		)
		(pad "1" smd circle
			(at 0.40005 0 270)
			(size 0 0)
			(layers "B.Cu" "B.Mask" "B.Paste")
			(net "P52V_HS1_GATE2_R")
		)
		(pad "2" smd circle
			(at -0.40005 0 270)
			(size 0 0)
			(layers "B.Cu" "B.Mask" "B.Paste")
			(net "P52V_HS1_4287_GATE2_R")
		)
	)
)
